# T6G (Grand Teton) — schematic netlist excerpt (pin names and nets, part order shuffled) for the footprints in the layout excerpt that follows; sources: Cadence DE-HDL packaged netlist, KiCad conversion of 04192023_DAF0TMB3IC0_F0TG_MB_C_brd_V02_OCP.brd

R572  Q_RES  20M 1% CHIP  pkg 0402LF  page 55 : A = XTAL_CPU1_R_X32K_X1 ; B = XTAL_CPU1_R_X32K_X2
C2271  Q_CAP  22UF 4V 20% X6S  pkg C0402  page 72 : A = PVDD11_S3_P1 ; B = GND
PC632_3  Q_CAP  22UF 16V 20% X6S  pkg C0805  page 223 : A = SW_P12V_AUX_PVDDIO_P1_FLT ; B = GND

(kicad_pcb
	(version 20260206)
	(generator "pcbnew")
	(generator_version "10.0")
	(general
		(thickness 1.6)
		(legacy_teardrops no)
	)
	(paper "A4")
	(title_block
		(title "04192023_DAF0TMB3IC0_F0TG_MB_C_brd_V02_OCP.brd")
		(comment 1 "Grand Teton / footprints 8051-8053 of 8354")
	)
	(layers
		(0 "F.Cu" signal "TOP")
		(4 "In1.Cu" signal "GND")
		(6 "In2.Cu" signal "IN1")
		(8 "In3.Cu" signal "GND1")
		(10 "In4.Cu" signal "IN2")
		(12 "In5.Cu" signal "GND2")
		(14 "In6.Cu" signal "IN3")
		(16 "In7.Cu" signal "GND3")
		(18 "In8.Cu" signal "VCC")
		(20 "In9.Cu" signal "VCC1")
		(22 "In10.Cu" signal "GND4")
		(24 "In11.Cu" signal "IN4")
		(26 "In12.Cu" signal "GND5")
		(28 "In13.Cu" signal "IN5")
		(30 "In14.Cu" signal "GND6")
		(32 "In15.Cu" signal "IN6")
		(34 "In16.Cu" signal "GND7")
		(2 "B.Cu" signal "BOTTOM")
		(9 "F.Adhes" user "F.Adhesive")
		(11 "B.Adhes" user "B.Adhesive")
		(13 "F.Paste" user "Package Geometry/Pastemask Top")
		(15 "B.Paste" user "Package Geometry/Pastemask Bottom")
		(5 "F.SilkS" user "Ref Des/Silkscreen Top")
		(7 "B.SilkS" user "Ref Des/Silkscreen Bottom")
		(1 "F.Mask" user "Board Geometry/Soldermask Top")
		(3 "B.Mask" user "Board Geometry/Soldermask Bottom")
		(17 "Dwgs.User" user "User.Drawings")
		(19 "Cmts.User" user "User.Comments")
		(21 "Eco1.User" user "User.Eco1")
		(23 "Eco2.User" user "User.Eco2")
		(25 "Edge.Cuts" user "Board Geometry/Outline")
		(27 "Margin" user)
		(31 "F.CrtYd" user "Package Geometry/Place Bound Top")
		(29 "B.CrtYd" user "Package Geometry/Place Bound Bottom")
		(35 "F.Fab" user "Ref Des/Assembly Top")
		(33 "B.Fab" user "Ref Des/Assembly Bottom")
	)
	(footprint ""
		(layer "B.Cu")
		(at 153.456386 -315.36005 180)
		(property "Reference" "R572"
			(at 0 0 0)
			(layer "B.SilkS")
			(hide yes)
			(effects
				(font
					(size 1.27 1.27)
				)
				(justify mirror)
			)
		)
		(property "Value" ""
			(at 0 0 0)
			(layer "B.Fab")
			(effects
				(font
					(size 1.27 1.27)
				)
				(justify mirror)
			)
		)
		(duplicate_pad_numbers_are_jumpers no)
		(fp_line
			(start 0.7874 0.4064)
			(end 0.7874 -0.4064)
			(stroke
				(width 0.1524)
				(type default)
			)
			(layer "B.SilkS")
		)
		(fp_line
			(start 0.7874 -0.4064)
			(end -0.7874 -0.4064)
			(stroke
				(width 0.1524)
				(type default)
			)
			(layer "B.SilkS")
		)
		(fp_line
			(start -0.7874 0.4064)
			(end 0.7874 0.4064)
			(stroke
				(width 0.1524)
				(type default)
			)
			(layer "B.SilkS")
		)
		(fp_line
			(start -0.7874 -0.4064)
			(end -0.7874 0.4064)
			(stroke
				(width 0.1524)
				(type default)
			)
			(layer "B.SilkS")
		)
		(fp_line
			(start 0.67945 0.3048)
			(end 0.67945 -0.305054)
			(stroke
				(width 0.1)
				(type default)
			)
			(layer "B.Fab")
		)
		(fp_line
			(start 0.67945 -0.305054)
			(end 0.12065 -0.305054)
			(stroke
				(width 0.1)
				(type default)
			)
			(layer "B.Fab")
		)
		(fp_line
			(start 0.12065 0.3048)
			(end 0.67945 0.3048)
			(stroke
				(width 0.1)
				(type default)
			)
			(layer "B.Fab")
		)
		(fp_line
			(start 0.12065 0.2794)
			(end 0.12065 0.3048)
			(stroke
				(width 0.1)
				(type default)
			)
			(layer "B.Fab")
		)
		(fp_line
			(start 0.12065 -0.2794)
			(end -0.12065 -0.2794)
			(stroke
				(width 0.1)
				(type default)
			)
			(layer "B.Fab")
		)
		(fp_line
			(start 0.12065 -0.305054)
			(end 0.12065 -0.2794)
			(stroke
				(width 0.1)
				(type default)
			)
			(layer "B.Fab")
		)
		(fp_line
			(start -0.120396 0.3048)
			(end -0.120396 0.2794)
			(stroke
				(width 0.1)
				(type default)
			)
			(layer "B.Fab")
		)
		(fp_line
			(start -0.120396 0.2794)
			(end 0.12065 0.2794)
			(stroke
				(width 0.1)
				(type default)
			)
			(layer "B.Fab")
		)
		(fp_line
			(start -0.12065 -0.2794)
			(end -0.12065 -0.3048)
			(stroke
				(width 0.1)
				(type default)
			)
			(layer "B.Fab")
		)
		(fp_line
			(start -0.12065 -0.3048)
			(end -0.67945 -0.3048)
			(stroke
				(width 0.1)
				(type default)
			)
			(layer "B.Fab")
		)
		(fp_line
			(start -0.67945 0.3048)
			(end -0.120396 0.3048)
			(stroke
				(width 0.1)
				(type default)
			)
			(layer "B.Fab")
		)
		(fp_line
			(start -0.67945 -0.3048)
			(end -0.67945 0.3048)
			(stroke
				(width 0.1)
				(type default)
			)
			(layer "B.Fab")
		)
		(pad "1" smd circle
			(at 0.40005 0)
			(size 0 0)
			(layers "B.Cu" "B.Mask" "B.Paste")
			(net "XTAL_CPU1_R_X32K_X1")
		)
		(pad "2" smd circle
			(at -0.40005 0)
			(size 0 0)
			(layers "B.Cu" "B.Mask" "B.Paste")
			(net "XTAL_CPU1_R_X32K_X2")
		)
	)
	(footprint ""
		(layer "B.Cu")
		(at 40.13073 -346.788994 90)
		(property "Reference" "PC632_3"
			(at 0 0 90)
			(layer "B.SilkS")
			(hide yes)
			(effects
				(font
					(size 1.27 1.27)
				)
				(justify mirror)
			)
		)
		(property "Value" ""
			(at 0 0 90)
			(layer "B.Fab")
			(effects
				(font
					(size 1.27 1.27)
				)
				(justify mirror)
			)
		)
		(duplicate_pad_numbers_are_jumpers no)
		(fp_line
			(start 1.524 -0.762)
			(end -1.524 -0.762)
			(stroke
				(width 0.1524)
				(type default)
			)
			(layer "B.SilkS")
		)
		(fp_line
			(start -1.524 -0.762)
			(end -1.524 0.762)
			(stroke
				(width 0.1524)
				(type default)
			)
			(layer "B.SilkS")
		)
		(fp_line
			(start 1.524 0.762)
			(end 1.524 -0.762)
			(stroke
				(width 0.1524)
				(type default)
			)
			(layer "B.SilkS")
		)
		(fp_line
			(start -1.524 0.762)
			(end 1.524 0.762)
			(stroke
				(width 0.1524)
				(type default)
			)
			(layer "B.SilkS")
		)
		(fp_line
			(start 1.1049 -0.724916)
			(end 1.1049 0.724916)
			(stroke
				(width 0.1)
				(type default)
			)
			(layer "B.Fab")
		)
		(fp_line
			(start -1.1049 -0.724916)
			(end 1.1049 -0.724916)
			(stroke
				(width 0.1)
				(type default)
			)
			(layer "B.Fab")
		)
		(fp_line
			(start 1.1049 0.724916)
			(end -1.1049 0.724916)
			(stroke
				(width 0.1)
				(type default)
			)
			(layer "B.Fab")
		)
		(fp_line
			(start -1.1049 0.724916)
			(end -1.1049 -0.724916)
			(stroke
				(width 0.1)
				(type default)
			)
			(layer "B.Fab")
		)
		(pad "1" smd rect
			(at 0.889 0 90)
			(size 1.016 1.27)
			(layers "B.Cu" "B.Mask" "B.Paste")
			(net "SW_P12V_AUX_PVDDIO_P1_FLT")
		)
		(pad "2" smd rect
			(at -0.889 0 90)
			(size 1.016 1.27)
			(layers "B.Cu" "B.Mask" "B.Paste")
			(net "GND")
		)
	)
	(footprint ""
		(layer "B.Cu")
		(at 116.227098 -261.748016 90)
		(property "Reference" "C2271"
			(at 0 0 90)
			(layer "B.SilkS")
			(hide yes)
			(effects
				(font
					(size 1.27 1.27)
				)
				(justify mirror)
			)
		)
		(property "Value" ""
			(at 0 0 90)
			(layer "B.Fab")
			(effects
				(font
					(size 1.27 1.27)
				)
				(justify mirror)
			)
		)
		(duplicate_pad_numbers_are_jumpers no)
		(fp_line
			(start 0.7874 -0.4064)
			(end -0.7874 -0.4064)
			(stroke
				(width 0.1524)
				(type default)
			)
			(layer "B.SilkS")
		)
		(fp_line
			(start -0.7874 -0.4064)
			(end -0.7874 0.4064)
			(stroke
				(width 0.1524)
				(type default)
			)
			(layer "B.SilkS")
		)
		(fp_line
			(start 0.7874 0.4064)
			(end 0.7874 -0.4064)
			(stroke
				(width 0.1524)
				(type default)
			)
			(layer "B.SilkS")
		)
		(fp_line
			(start -0.7874 0.4064)
			(end 0.7874 0.4064)
			(stroke
				(width 0.1524)
				(type default)
			)
			(layer "B.SilkS")
		)
		(fp_line
			(start 0.67945 -0.305054)
			(end 0.12065 -0.305054)
			(stroke
				(width 0.1)
				(type default)
			)
			(layer "B.Fab")
		)
		(fp_line
			(start 0.12065 -0.305054)
			(end 0.12065 -0.2794)
			(stroke
				(width 0.1)
				(type default)
			)
			(layer "B.Fab")
		)
		(fp_line
			(start -0.12065 -0.3048)
			(end -0.67945 -0.3048)
			(stroke
				(width 0.1)
				(type default)
			)
			(layer "B.Fab")
		)
		(fp_line
			(start -0.67945 -0.3048)
			(end -0.67945 0.3048)
			(stroke
				(width 0.1)
				(type default)
			)
			(layer "B.Fab")
		)
		(fp_line
			(start 0.12065 -0.2794)
			(end -0.12065 -0.2794)
			(stroke
				(width 0.1)
				(type default)
			)
			(layer "B.Fab")
		)
		(fp_line
			(start -0.12065 -0.2794)
			(end -0.12065 -0.3048)
			(stroke
				(width 0.1)
				(type default)
			)
			(layer "B.Fab")
		)
		(fp_line
			(start 0.12065 0.2794)
			(end 0.12065 0.3048)
			(stroke
				(width 0.1)
				(type default)
			)
			(layer "B.Fab")
		)
		(fp_line
			(start -0.120396 0.2794)
			(end 0.12065 0.2794)
			(stroke
				(width 0.1)
				(type default)
			)
			(layer "B.Fab")
		)
		(fp_line
			(start 0.67945 0.3048)
			(end 0.67945 -0.305054)
			(stroke
				(width 0.1)
				(type default)
			)
			(layer "B.Fab")
		)
		(fp_line
			(start 0.12065 0.3048)
			(end 0.67945 0.3048)
			(stroke
				(width 0.1)
				(type default)
			)
			(layer "B.Fab")
		)
		(fp_line
			(start -0.120396 0.3048)
			(end -0.120396 0.2794)
			(stroke
				(width 0.1)
				(type default)
			)
			(layer "B.Fab")
		)
		(fp_line
			(start -0.67945 0.3048)
			(end -0.120396 0.3048)
			(stroke
				(width 0.1)
				(type default)
			)
			(layer "B.Fab")
		)
		(pad "1" smd circle
			(at 0.40005 0 270)
			(size 0 0)
			(layers "B.Cu" "B.Mask" "B.Paste")
			(net "PVDD11_S3_P1")
		)
		(pad "2" smd circle
			(at -0.40005 0 270)
			(size 0 0)
			(layers "B.Cu" "B.Mask" "B.Paste")
			(net "GND")
		)
	)
)
